(kicad_pcb
	(version 20241229)
	(generator "pcbnew")
	(generator_version "9.0")
	(general
		(thickness 1.599998)
		(legacy_teardrops no)
	)
	(paper "A4")
	(title_block
		(title "Artix - Datacenter Secure Control Module (DC-SCM)")
		(date "2024-11-06")
		(rev "1.1.3")
		(comment 9 "footprints 25-30 of 544")
	)
	(layers
		(0 "F.Cu" signal)
		(4 "In1.Cu" signal)
		(6 "In2.Cu" signal)
		(8 "In3.Cu" signal)
		(10 "In4.Cu" signal)
		(12 "In5.Cu" signal)
		(14 "In6.Cu" signal)
		(2 "B.Cu" signal)
		(9 "F.Adhes" user "F.Adhesive")
		(11 "B.Adhes" user "B.Adhesive")
		(13 "F.Paste" user)
		(15 "B.Paste" user)
		(5 "F.SilkS" user "F.Silkscreen")
		(7 "B.SilkS" user "B.Silkscreen")
		(1 "F.Mask" user)
		(3 "B.Mask" user)
		(17 "Dwgs.User" user "User.Drawings")
		(19 "Cmts.User" user "User.Comments")
		(21 "Eco1.User" user "User.Eco1")
		(23 "Eco2.User" user "User.Eco2")
		(25 "Edge.Cuts" user)
		(27 "Margin" user)
		(31 "F.CrtYd" user "F.Courtyard")
		(29 "B.CrtYd" user "B.Courtyard")
		(35 "F.Fab" user)
		(33 "B.Fab" user)
	)
	(footprint "antmicro-footprints:C_0402_1005Metric"
		(layer "F.Cu")
		(at 85.895 94.175 180)
		(descr "Capacitor SMD 0402")
		(tags "capacitor SMD 0402")
		(property "Reference" "C84"
			(at -3.005 -0.325 0)
			(layer "F.SilkS")
			(effects
				(font
					(size 0.7 0.7)
					(thickness 0.15)
				)
				(justify right bottom)
			)
		)
		(property "Value" "C_10u_0402"
			(at 0 1.4 0)
			(layer "F.Fab")
			(effects
				(font
					(size 0.7 0.7)
					(thickness 0.15)
				)
				(justify right bottom)
			)
		)
		(property "Datasheet" "https://www.yageo.com/en/Chart/Download/pdf/CC0402MRX5R5BB106"
			(at 0 0 180)
			(layer "F.Fab")
			(hide yes)
			(effects
				(font
					(size 1.27 1.27)
					(thickness 0.15)
				)
			)
		)
		(property "Description" "SMD Multilayer Ceramic Capacitor, 10 µF, 6.3 V, 0402 [1005 Metric], ± 20%, X5R, CC Series"
			(at 0 0 180)
			(layer "F.Fab")
			(hide yes)
			(effects
				(font
					(size 1.27 1.27)
					(thickness 0.15)
				)
			)
		)
		(property "Author" "Antmicro"
			(at 171.79 188.35 0)
			(layer "F.Fab")
			(hide yes)
			(effects
				(font
					(size 1 1)
					(thickness 0.15)
				)
			)
		)
		(property "Dielectric" ""
			(at 171.79 188.35 0)
			(layer "F.Fab")
			(hide yes)
			(effects
				(font
					(size 1 1)
					(thickness 0.15)
				)
			)
		)
		(property "License" "Apache-2.0"
			(at 171.79 188.35 0)
			(layer "F.Fab")
			(hide yes)
			(effects
				(font
					(size 1 1)
					(thickness 0.15)
				)
			)
		)
		(property "MPN" "CC0402MRX5R5BB106"
			(at 171.79 188.35 0)
			(layer "F.Fab")
			(hide yes)
			(effects
				(font
					(size 1 1)
					(thickness 0.15)
				)
			)
		)
		(property "Manufacturer" "YAGEO"
			(at 171.79 188.35 0)
			(layer "F.Fab")
			(hide yes)
			(effects
				(font
					(size 1 1)
					(thickness 0.15)
				)
			)
		)
		(property "Val" "10u"
			(at 171.79 188.35 0)
			(layer "F.Fab")
			(hide yes)
			(effects
				(font
					(size 1 1)
					(thickness 0.15)
				)
			)
		)
		(property "Voltage" ""
			(at 171.79 188.35 0)
			(layer "F.Fab")
			(hide yes)
			(effects
				(font
					(size 1 1)
					(thickness 0.15)
				)
			)
		)
		(sheetname "/Power supply/")
		(sheetfile "power-supply.kicad_sch")
		(attr smd)
		(fp_rect
			(start -0.925 -0.47)
			(end 0.925 0.47)
			(stroke
				(width 0.05)
				(type default)
			)
			(fill no)
			(layer "F.CrtYd")
		)
		(fp_line
			(start 0.504 0.248)
			(end -0.494 0.248)
			(stroke
				(width 0.15)
				(type solid)
			)
			(layer "F.Fab")
		)
		(fp_line
			(start 0.504 -0.25)
			(end 0.504 0.248)
			(stroke
				(width 0.15)
				(type solid)
			)
			(layer "F.Fab")
		)
		(fp_line
			(start -0.494 0.248)
			(end -0.494 -0.25)
			(stroke
				(width 0.15)
				(type solid)
			)
			(layer "F.Fab")
		)
		(fp_line
			(start -0.494 -0.25)
			(end 0.504 -0.25)
			(stroke
				(width 0.15)
				(type solid)
			)
			(layer "F.Fab")
		)
		(pad "1" smd roundrect
			(at -0.48 0 180)
			(size 0.59 0.64)
			(layers "F.Cu" "F.Mask" "F.Paste")
			(roundrect_rratio 0.25)
			(net 1 "GND")
			(pintype "passive")
		)
		(pad "2" smd roundrect
			(at 0.48 0 180)
			(size 0.59 0.64)
			(layers "F.Cu" "F.Mask" "F.Paste")
			(roundrect_rratio 0.25)
			(net 275 "Net-(C80-Pad2)")
			(pintype "passive")
		)
	)
	(footprint "antmicro-footprints:C_0402_1005Metric"
		(layer "F.Cu")
		(at 86.789 101.514 180)
		(descr "Capacitor SMD 0402")
		(tags "capacitor SMD 0402")
		(property "Reference" "C83"
			(at -3.026 -0.386 0)
			(layer "F.SilkS")
			(effects
				(font
					(size 0.7 0.7)
					(thickness 0.15)
				)
				(justify right bottom)
			)
		)
		(property "Value" "C_10u_0402"
			(at 0 1.4 0)
			(layer "F.Fab")
			(effects
				(font
					(size 0.7 0.7)
					(thickness 0.15)
				)
				(justify right bottom)
			)
		)
		(property "Datasheet" "https://www.yageo.com/en/Chart/Download/pdf/CC0402MRX5R5BB106"
			(at 0 0 180)
			(layer "F.Fab")
			(hide yes)
			(effects
				(font
					(size 1.27 1.27)
					(thickness 0.15)
				)
			)
		)
		(property "Description" "SMD Multilayer Ceramic Capacitor, 10 µF, 6.3 V, 0402 [1005 Metric], ± 20%, X5R, CC Series"
			(at 0 0 180)
			(layer "F.Fab")
			(hide yes)
			(effects
				(font
					(size 1.27 1.27)
					(thickness 0.15)
				)
			)
		)
		(property "Author" "Antmicro"
			(at 173.578 203.028 0)
			(layer "F.Fab")
			(hide yes)
			(effects
				(font
					(size 1 1)
					(thickness 0.15)
				)
			)
		)
		(property "Dielectric" ""
			(at 173.578 203.028 0)
			(layer "F.Fab")
			(hide yes)
			(effects
				(font
					(size 1 1)
					(thickness 0.15)
				)
			)
		)
		(property "License" "Apache-2.0"
			(at 173.578 203.028 0)
			(layer "F.Fab")
			(hide yes)
			(effects
				(font
					(size 1 1)
					(thickness 0.15)
				)
			)
		)
		(property "MPN" "CC0402MRX5R5BB106"
			(at 173.578 203.028 0)
			(layer "F.Fab")
			(hide yes)
			(effects
				(font
					(size 1 1)
					(thickness 0.15)
				)
			)
		)
		(property "Manufacturer" "YAGEO"
			(at 173.578 203.028 0)
			(layer "F.Fab")
			(hide yes)
			(effects
				(font
					(size 1 1)
					(thickness 0.15)
				)
			)
		)
		(property "Val" "10u"
			(at 173.578 203.028 0)
			(layer "F.Fab")
			(hide yes)
			(effects
				(font
					(size 1 1)
					(thickness 0.15)
				)
			)
		)
		(property "Voltage" ""
			(at 173.578 203.028 0)
			(layer "F.Fab")
			(hide yes)
			(effects
				(font
					(size 1 1)
					(thickness 0.15)
				)
			)
		)
		(sheetname "/Power supply/")
		(sheetfile "power-supply.kicad_sch")
		(attr smd)
		(fp_rect
			(start -0.925 -0.47)
			(end 0.925 0.47)
			(stroke
				(width 0.05)
				(type default)
			)
			(fill no)
			(layer "F.CrtYd")
		)
		(fp_line
			(start 0.504 0.248)
			(end -0.494 0.248)
			(stroke
				(width 0.15)
				(type solid)
			)
			(layer "F.Fab")
		)
		(fp_line
			(start 0.504 -0.25)
			(end 0.504 0.248)
			(stroke
				(width 0.15)
				(type solid)
			)
			(layer "F.Fab")
		)
		(fp_line
			(start -0.494 0.248)
			(end -0.494 -0.25)
			(stroke
				(width 0.15)
				(type solid)
			)
			(layer "F.Fab")
		)
		(fp_line
			(start -0.494 -0.25)
			(end 0.504 -0.25)
			(stroke
				(width 0.15)
				(type solid)
			)
			(layer "F.Fab")
		)
		(pad "1" smd roundrect
			(at -0.48 0 180)
			(size 0.59 0.64)
			(layers "F.Cu" "F.Mask" "F.Paste")
			(roundrect_rratio 0.25)
			(net 1 "GND")
			(pintype "passive")
		)
		(pad "2" smd roundrect
			(at 0.48 0 180)
			(size 0.59 0.64)
			(layers "F.Cu" "F.Mask" "F.Paste")
			(roundrect_rratio 0.25)
			(net 274 "Net-(C79-Pad2)")
			(pintype "passive")
		)
	)
	(footprint "antmicro-footprints:R_0402_1005Metric"
		(layer "F.Cu")
		(at 89.549 103.927 90)
		(descr "Resistor SMD 0402")
		(tags "resistor SMD 0402")
		(property "Reference" "R74"
			(at -0.973 3.351 90)
			(layer "F.SilkS")
			(effects
				(font
					(size 0.7 0.7)
					(thickness 0.15)
				)
				(justify left bottom)
			)
		)
		(property "Value" "R_100k_0402"
			(at 0 1.4 90)
			(layer "F.Fab")
			(effects
				(font
					(size 0.7 0.7)
					(thickness 0.15)
				)
				(justify left bottom)
			)
		)
		(property "Datasheet" "https://www.bourns.com/docs/product-datasheets/cr.pdf"
			(at 0 0 90)
			(layer "F.Fab")
			(hide yes)
			(effects
				(font
					(size 1.27 1.27)
					(thickness 0.15)
				)
			)
		)
		(property "Description" "SMD Chip Resistor, 100 kohm, ± 1%, 62.5 mW, 0402 [1005 Metric], Thick Film, General Purpose"
			(at 0 0 90)
			(layer "F.Fab")
			(hide yes)
			(effects
				(font
					(size 1.27 1.27)
					(thickness 0.15)
				)
			)
		)
		(property "Author" "Antmicro"
			(at 193.476 14.378 0)
			(layer "F.Fab")
			(hide yes)
			(effects
				(font
					(size 1 1)
					(thickness 0.15)
				)
			)
		)
		(property "License" "Apache-2.0"
			(at 193.476 14.378 0)
			(layer "F.Fab")
			(hide yes)
			(effects
				(font
					(size 1 1)
					(thickness 0.15)
				)
			)
		)
		(property "MPN" "CR0402-FX-1003GLF"
			(at 193.476 14.378 0)
			(layer "F.Fab")
			(hide yes)
			(effects
				(font
					(size 1 1)
					(thickness 0.15)
				)
			)
		)
		(property "Manufacturer" "Bourns"
			(at 193.476 14.378 0)
			(layer "F.Fab")
			(hide yes)
			(effects
				(font
					(size 1 1)
					(thickness 0.15)
				)
			)
		)
		(property "Tolerance" "1%"
			(at 193.476 14.378 0)
			(layer "F.Fab")
			(hide yes)
			(effects
				(font
					(size 1 1)
					(thickness 0.15)
				)
			)
		)
		(property "Val" "100k"
			(at 193.476 14.378 0)
			(layer "F.Fab")
			(hide yes)
			(effects
				(font
					(size 1 1)
					(thickness 0.15)
				)
			)
		)
		(sheetname "/Power supply/")
		(sheetfile "power-supply.kicad_sch")
		(attr smd)
		(fp_rect
			(start -0.925 -0.47)
			(end 0.925 0.47)
			(stroke
				(width 0.05)
				(type default)
			)
			(fill no)
			(layer "F.CrtYd")
		)
		(fp_rect
			(start -0.5 -0.25)
			(end 0.5 0.25)
			(stroke
				(width 0.15)
				(type solid)
			)
			(fill no)
			(layer "F.Fab")
		)
		(pad "1" smd roundrect
			(at -0.48 0 90)
			(size 0.59 0.64)
			(layers "F.Cu" "F.Mask" "F.Paste")
			(roundrect_rratio 0.25)
			(net 113 "Net-(U10-FB)")
			(pintype "passive")
		)
		(pad "2" smd roundrect
			(at 0.48 0 90)
			(size 0.59 0.64)
			(layers "F.Cu" "F.Mask" "F.Paste")
			(roundrect_rratio 0.25)
			(net 1 "GND")
			(pintype "passive")
		)
	)
	(footprint "antmicro-footprints:R_0402_1005Metric"
		(layer "F.Cu")
		(at 90.545 96.575 90)
		(descr "Resistor SMD 0402")
		(tags "resistor SMD 0402")
		(property "Reference" "R75"
			(at 0.775 0.355 90)
			(layer "F.SilkS")
			(effects
				(font
					(size 0.7 0.7)
					(thickness 0.15)
				)
				(justify left bottom)
			)
		)
		(property "Value" "R_200k_0402"
			(at 0 1.4 90)
			(layer "F.Fab")
			(effects
				(font
					(size 0.7 0.7)
					(thickness 0.15)
				)
				(justify left bottom)
			)
		)
		(property "Datasheet" "https://www.bourns.com/docs/product-datasheets/cr.pdf"
			(at 0 0 90)
			(layer "F.Fab")
			(hide yes)
			(effects
				(font
					(size 1.27 1.27)
					(thickness 0.15)
				)
			)
		)
		(property "Description" "SMD Chip Resistor, 200 kohm, ± 1%, 62.5 mW, 0402 [1005 Metric], Thick Film, General Purpose"
			(at 0 0 90)
			(layer "F.Fab")
			(hide yes)
			(effects
				(font
					(size 1.27 1.27)
					(thickness 0.15)
				)
			)
		)
		(property "Author" "Antmicro"
			(at 187.12 6.03 0)
			(layer "F.Fab")
			(hide yes)
			(effects
				(font
					(size 1 1)
					(thickness 0.15)
				)
			)
		)
		(property "License" "Apache-2.0"
			(at 187.12 6.03 0)
			(layer "F.Fab")
			(hide yes)
			(effects
				(font
					(size 1 1)
					(thickness 0.15)
				)
			)
		)
		(property "MPN" "CR0402-FX-2003GLF"
			(at 187.12 6.03 0)
			(layer "F.Fab")
			(hide yes)
			(effects
				(font
					(size 1 1)
					(thickness 0.15)
				)
			)
		)
		(property "Manufacturer" "Bourns"
			(at 187.12 6.03 0)
			(layer "F.Fab")
			(hide yes)
			(effects
				(font
					(size 1 1)
					(thickness 0.15)
				)
			)
		)
		(property "Tolerance" "1%"
			(at 187.12 6.03 0)
			(layer "F.Fab")
			(hide yes)
			(effects
				(font
					(size 1 1)
					(thickness 0.15)
				)
			)
		)
		(property "Val" "200k"
			(at 187.12 6.03 0)
			(layer "F.Fab")
			(hide yes)
			(effects
				(font
					(size 1 1)
					(thickness 0.15)
				)
			)
		)
		(sheetname "/Power supply/")
		(sheetfile "power-supply.kicad_sch")
		(attr smd)
		(fp_rect
			(start -0.925 -0.47)
			(end 0.925 0.47)
			(stroke
				(width 0.05)
				(type default)
			)
			(fill no)
			(layer "F.CrtYd")
		)
		(fp_rect
			(start -0.5 -0.25)
			(end 0.5 0.25)
			(stroke
				(width 0.15)
				(type solid)
			)
			(fill no)
			(layer "F.Fab")
		)
		(pad "1" smd roundrect
			(at -0.48 0 90)
			(size 0.59 0.64)
			(layers "F.Cu" "F.Mask" "F.Paste")
			(roundrect_rratio 0.25)
			(net 117 "Net-(U11-FB)")
			(pintype "passive")
		)
		(pad "2" smd roundrect
			(at 0.48 0 90)
			(size 0.59 0.64)
			(layers "F.Cu" "F.Mask" "F.Paste")
			(roundrect_rratio 0.25)
			(net 275 "Net-(C80-Pad2)")
			(pintype "passive")
		)
	)
	(footprint "antmicro-footprints:C_0402_1005Metric"
		(layer "F.Cu")
		(at 86.774 100.114 180)
		(descr "Capacitor SMD 0402")
		(tags "capacitor SMD 0402")
		(property "Reference" "C87"
			(at -3.026 -0.386 0)
			(layer "F.SilkS")
			(effects
				(font
					(size 0.7 0.7)
					(thickness 0.15)
				)
				(justify right bottom)
			)
		)
		(property "Value" "C_10u_0402"
			(at 0 1.4 0)
			(layer "F.Fab")
			(effects
				(font
					(size 0.7 0.7)
					(thickness 0.15)
				)
				(justify right bottom)
			)
		)
		(property "Datasheet" "https://www.yageo.com/en/Chart/Download/pdf/CC0402MRX5R5BB106"
			(at 0 0 180)
			(layer "F.Fab")
			(hide yes)
			(effects
				(font
					(size 1.27 1.27)
					(thickness 0.15)
				)
			)
		)
		(property "Description" "SMD Multilayer Ceramic Capacitor, 10 µF, 6.3 V, 0402 [1005 Metric], ± 20%, X5R, CC Series"
			(at 0 0 180)
			(layer "F.Fab")
			(hide yes)
			(effects
				(font
					(size 1.27 1.27)
					(thickness 0.15)
				)
			)
		)
		(property "Author" "Antmicro"
			(at 173.548 200.228 0)
			(layer "F.Fab")
			(hide yes)
			(effects
				(font
					(size 1 1)
					(thickness 0.15)
				)
			)
		)
		(property "Dielectric" ""
			(at 173.548 200.228 0)
			(layer "F.Fab")
			(hide yes)
			(effects
				(font
					(size 1 1)
					(thickness 0.15)
				)
			)
		)
		(property "License" "Apache-2.0"
			(at 173.548 200.228 0)
			(layer "F.Fab")
			(hide yes)
			(effects
				(font
					(size 1 1)
					(thickness 0.15)
				)
			)
		)
		(property "MPN" "CC0402MRX5R5BB106"
			(at 173.548 200.228 0)
			(layer "F.Fab")
			(hide yes)
			(effects
				(font
					(size 1 1)
					(thickness 0.15)
				)
			)
		)
		(property "Manufacturer" "YAGEO"
			(at 173.548 200.228 0)
			(layer "F.Fab")
			(hide yes)
			(effects
				(font
					(size 1 1)
					(thickness 0.15)
				)
			)
		)
		(property "Val" "10u"
			(at 173.548 200.228 0)
			(layer "F.Fab")
			(hide yes)
			(effects
				(font
					(size 1 1)
					(thickness 0.15)
				)
			)
		)
		(property "Voltage" ""
			(at 173.548 200.228 0)
			(layer "F.Fab")
			(hide yes)
			(effects
				(font
					(size 1 1)
					(thickness 0.15)
				)
			)
		)
		(sheetname "/Power supply/")
		(sheetfile "power-supply.kicad_sch")
		(attr smd)
		(fp_rect
			(start -0.925 -0.47)
			(end 0.925 0.47)
			(stroke
				(width 0.05)
				(type default)
			)
			(fill no)
			(layer "F.CrtYd")
		)
		(fp_line
			(start 0.504 0.248)
			(end -0.494 0.248)
			(stroke
				(width 0.15)
				(type solid)
			)
			(layer "F.Fab")
		)
		(fp_line
			(start 0.504 -0.25)
			(end 0.504 0.248)
			(stroke
				(width 0.15)
				(type solid)
			)
			(layer "F.Fab")
		)
		(fp_line
			(start -0.494 0.248)
			(end -0.494 -0.25)
			(stroke
				(width 0.15)
				(type solid)
			)
			(layer "F.Fab")
		)
		(fp_line
			(start -0.494 -0.25)
			(end 0.504 -0.25)
			(stroke
				(width 0.15)
				(type solid)
			)
			(layer "F.Fab")
		)
		(pad "1" smd roundrect
			(at -0.48 0 180)
			(size 0.59 0.64)
			(layers "F.Cu" "F.Mask" "F.Paste")
			(roundrect_rratio 0.25)
			(net 1 "GND")
			(pintype "passive")
		)
		(pad "2" smd roundrect
			(at 0.48 0 180)
			(size 0.59 0.64)
			(layers "F.Cu" "F.Mask" "F.Paste")
			(roundrect_rratio 0.25)
			(net 274 "Net-(C79-Pad2)")
			(pintype "passive")
		)
	)
	(footprint "antmicro-footprints:C_0603_1608Metric"
		(layer "F.Cu")
		(at 85.1 96.5 -90)
		(descr "Capacitor SMD 0603")
		(tags "capacitor 0603")
		(property "Reference" "C76"
			(at 2.25 0.94 270)
			(layer "F.SilkS")
			(effects
				(font
					(size 0.7 0.7)
					(thickness 0.15)
				)
				(justify left bottom)
			)
		)
		(property "Value" "C_10u_0603"
			(at 0 1.6 270)
			(layer "F.Fab")
			(effects
				(font
					(size 0.7 0.7)
					(thickness 0.15)
				)
				(justify left bottom)
			)
		)
		(property "Datasheet" "https://www.murata.com/products/productdetail?partno=GRM188R61A106KE69%23"
			(at 0 0 270)
			(layer "F.Fab")
			(hide yes)
			(effects
				(font
					(size 1.27 1.27)
					(thickness 0.15)
				)
			)
		)
		(property "Description" "SMD Multilayer Ceramic Capacitor, 10 µF, 10 V, 0603 [1608 Metric], ± 10%, X5R, GRM Series"
			(at 0 0 270)
			(layer "F.Fab")
			(hide yes)
			(effects
				(font
					(size 1.27 1.27)
					(thickness 0.15)
				)
			)
		)
		(property "Author" "Antmicro"
			(at -11.4 181.6 0)
			(layer "F.Fab")
			(hide yes)
			(effects
				(font
					(size 1 1)
					(thickness 0.15)
				)
			)
		)
		(property "Dielectric" "template_dielectric"
			(at -11.4 181.6 0)
			(layer "F.Fab")
			(hide yes)
			(effects
				(font
					(size 1 1)
					(thickness 0.15)
				)
			)
		)
		(property "License" "Apache-2.0"
			(at -11.4 181.6 0)
			(layer "F.Fab")
			(hide yes)
			(effects
				(font
					(size 1 1)
					(thickness 0.15)
				)
			)
		)
		(property "MPN" "GRM188R61A106KE69D"
			(at -11.4 181.6 0)
			(layer "F.Fab")
			(hide yes)
			(effects
				(font
					(size 1 1)
					(thickness 0.15)
				)
			)
		)
		(property "Manufacturer" "Murata"
			(at -11.4 181.6 0)
			(layer "F.Fab")
			(hide yes)
			(effects
				(font
					(size 1 1)
					(thickness 0.15)
				)
			)
		)
		(property "Val" "10u"
			(at -11.4 181.6 0)
			(layer "F.Fab")
			(hide yes)
			(effects
				(font
					(size 1 1)
					(thickness 0.15)
				)
			)
		)
		(property "Voltage" ""
			(at -11.4 181.6 0)
			(layer "F.Fab")
			(hide yes)
			(effects
				(font
					(size 1 1)
					(thickness 0.15)
				)
			)
		)
		(sheetname "/Power supply/")
		(sheetfile "power-supply.kicad_sch")
		(attr smd)
		(fp_line
			(start -0.15 0.4)
			(end 0.15 0.4)
			(stroke
				(width 0.15)
				(type solid)
			)
			(layer "F.SilkS")
		)
		(fp_line
			(start -0.15 -0.4)
			(end 0.15 -0.4)
			(stroke
				(width 0.15)
				(type solid)
			)
			(layer "F.SilkS")
		)
		(fp_rect
			(start -1.25 -0.65)
			(end 1.25 0.65)
			(stroke
				(width 0.05)
				(type solid)
			)
			(fill no)
			(layer "F.CrtYd")
		)
		(fp_rect
			(start -0.8 -0.4)
			(end 0.8 0.4)
			(stroke
				(width 0.15)
				(type solid)
			)
			(fill no)
			(layer "F.Fab")
		)
		(pad "1" smd roundrect
			(at -0.7 0 270)
			(size 0.8 1)
			(layers "F.Cu" "F.Mask" "F.Paste")
			(roundrect_rratio 0.2)
			(net 1 "GND")
			(pintype "passive")
		)
		(pad "2" smd roundrect
			(at 0.7 0 270)
			(size 0.8 1)
			(layers "F.Cu" "F.Mask" "F.Paste")
			(roundrect_rratio 0.2)
			(net 4 "VCC5V0")
			(pintype "passive")
		)
	)
)
